(kicad_pcb
	(version 20260206)
	(generator "pcbnew")
	(generator_version "10.0")
	(general
		(thickness 1.5755)
		(legacy_teardrops no)
	)
	(paper "A4")
	(title_block
		(title "gnss-neo-m9n — 844-XXXXX_FAB_NEO-M9N_MODULE.PcbDoc")
		(comment 1 "Time Appliance Project (Time Card) / footprints 1-11 of 33")
	)
	(layers
		(0 "F.Cu" signal "L01-Top Layer")
		(4 "In1.Cu" signal "L02-Inner Layer")
		(6 "In2.Cu" signal "L03-Inner Layer")
		(2 "B.Cu" signal "L04-Bottom Layer")
		(9 "F.Adhes" user "F.Adhesive")
		(11 "B.Adhes" user "B.Adhesive")
		(13 "F.Paste" user "Top Paste")
		(15 "B.Paste" user "Bottom Paste")
		(5 "F.SilkS" user "Top Overlay")
		(7 "B.SilkS" user "Bottom Overlay")
		(1 "F.Mask" user "Top Solder")
		(3 "B.Mask" user "Bottom Solder")
		(17 "Dwgs.User" user "User.Drawings")
		(19 "Cmts.User" user "User.Comments")
		(21 "Eco1.User" user "User.Eco1")
		(23 "Eco2.User" user "User.Eco2")
		(25 "Edge.Cuts" user)
		(27 "Margin" user)
		(31 "F.CrtYd" user "Top Courtyard")
		(29 "B.CrtYd" user "Bottom Courtyard")
		(35 "F.Fab" user "Top Component Outline")
		(33 "B.Fab" user "Bottom Component Outline 2")
		(39 "User.1" user "M01_PCB_Outline")
	)
	(footprint "MyLibrary:led0603"
		(layer "F.Cu")
		(at 165.96429 110.401495 90)
		(property "Reference" "LED2"
			(at 3.4032 0.073243 90)
			(unlocked yes)
			(layer "F.SilkS")
			(effects
				(font
					(size 0.635 0.635)
					(thickness 0.1778)
				)
			)
		)
		(property "Value" "Green"
			(at -3.032583 3.262745 0)
			(unlocked yes)
			(layer "F.SilkS")
			(hide yes)
			(effects
				(font
					(size 0.635 0.635)
					(thickness 0.1778)
				)
			)
		)
		(sheetname "846-XXXXX_SCH_NEO-M9N_MODULE_2_RECEIVER")
		(sheetfile "846-XXXXX_SCH_NEO-M9N_MODULE_2_RECEIVER.kicad_sch")
		(duplicate_pad_numbers_are_jumpers no)
		(fp_line
			(start 1.397 -0.635)
			(end 1.397 0.635)
			(stroke
				(width 0.1778)
				(type solid)
			)
			(layer "F.SilkS")
		)
		(fp_line
			(start -1.397 -0.635)
			(end 1.397 -0.635)
			(stroke
				(width 0.1778)
				(type solid)
			)
			(layer "F.SilkS")
		)
		(fp_line
			(start -1.397 -0.635)
			(end -1.397 0.635)
			(stroke
				(width 0.1778)
				(type solid)
			)
			(layer "F.SilkS")
		)
		(fp_line
			(start -0.03175 -0.12065)
			(end 0.08255 -0.00635)
			(stroke
				(width 0.0762)
				(type solid)
			)
			(layer "F.SilkS")
		)
		(fp_line
			(start -0.03175 -0.12065)
			(end -0.03175 0.10795)
			(stroke
				(width 0.0762)
				(type solid)
			)
			(layer "F.SilkS")
		)
		(fp_line
			(start 0.08255 -0.00635)
			(end -0.03175 0.10795)
			(stroke
				(width 0.0762)
				(type solid)
			)
			(layer "F.SilkS")
		)
		(fp_line
			(start -1.397 0.635)
			(end 1.397 0.635)
			(stroke
				(width 0.1778)
				(type solid)
			)
			(layer "F.SilkS")
		)
		(fp_rect
			(start -0.032105 0.048195)
			(end 0.036975 -0.052755)
			(stroke
				(width 0)
				(type default)
			)
			(fill yes)
			(layer "F.SilkS")
		)
		(pad "1" smd rect
			(at -0.75 0 90)
			(size 0.8 0.8)
			(layers "F.Cu" "F.Mask" "F.Paste")
			(net "+3V3")
		)
		(pad "2" smd rect
			(at 0.75 0 90)
			(size 0.8 0.8)
			(layers "F.Cu" "F.Mask" "F.Paste")
			(net "NetLED2_2")
		)
	)
	(footprint "MyLibrary:TP1MM"
		(layer "F.Cu")
		(at 149.31461 97.161445)
		(property "Reference" "TP5"
			(at 0.022933 -1.763155 90)
			(unlocked yes)
			(layer "F.SilkS")
			(effects
				(font
					(size 0.635 0.635)
					(thickness 0.1778)
				)
			)
		)
		(property "Value" "1MM"
			(at -2.092783 1.790085 270)
			(unlocked yes)
			(layer "F.SilkS")
			(hide yes)
			(effects
				(font
					(size 0.635 0.635)
					(thickness 0.1778)
				)
			)
		)
		(sheetname "846-XXXXX_SCH_NEO-M9N_MODULE_2_RECEIVER")
		(sheetfile "846-XXXXX_SCH_NEO-M9N_MODULE_2_RECEIVER.kicad_sch")
		(duplicate_pad_numbers_are_jumpers no)
		(pad "1" smd circle
			(at 0 0)
			(size 1 1)
			(layers "F.Cu" "F.Mask" "F.Paste")
			(net "EXTIN")
			(solder_paste_margin -100)
			(thermal_bridge_angle 90)
		)
	)
	(footprint "MyLibrary:c0402"
		(layer "F.Cu")
		(at 153.21407 114.176095 90)
		(property "Reference" "C3"
			(at -3.083605 -0.122443 270)
			(unlocked yes)
			(layer "F.SilkS")
			(effects
				(font
					(size 0.635 0.635)
					(thickness 0.1778)
				)
			)
		)
		(property "Value" "10nF 50V 0402"
			(at 5.065455 2.118183 90)
			(unlocked yes)
			(layer "F.SilkS")
			(hide yes)
			(effects
				(font
					(size 0.635 0.635)
					(thickness 0.1778)
				)
			)
		)
		(sheetname "846-XXXXX_SCH_NEO-M9N_MODULE_2_RECEIVER")
		(sheetfile "846-XXXXX_SCH_NEO-M9N_MODULE_2_RECEIVER.kicad_sch")
		(duplicate_pad_numbers_are_jumpers no)
		(fp_line
			(start 0.9906 -0.4826)
			(end 0.9906 0.4826)
			(stroke
				(width 0.1778)
				(type solid)
			)
			(layer "F.SilkS")
		)
		(fp_line
			(start -0.9906 -0.4826)
			(end 0.9906 -0.4826)
			(stroke
				(width 0.1778)
				(type solid)
			)
			(layer "F.SilkS")
		)
		(fp_line
			(start -0.9906 -0.4826)
			(end -0.9906 0.4826)
			(stroke
				(width 0.1778)
				(type solid)
			)
			(layer "F.SilkS")
		)
		(fp_line
			(start -0.9906 0.4826)
			(end 0.9906 0.4826)
			(stroke
				(width 0.1778)
				(type solid)
			)
			(layer "F.SilkS")
		)
		(pad "1" smd rect
			(at -0.5 0 90)
			(size 0.5 0.5)
			(layers "F.Cu" "F.Mask" "F.Paste")
			(net "GND")
		)
		(pad "2" smd rect
			(at 0.5 0 90)
			(size 0.5 0.5)
			(layers "F.Cu" "F.Mask" "F.Paste")
			(net "+3V3")
		)
	)
	(footprint "MyLibrary:c0402"
		(layer "F.Cu")
		(at 139.71595 96.476095 -90)
		(property "Reference" "C4"
			(at -2.177805 -0.021583 90)
			(unlocked yes)
			(layer "F.SilkS")
			(effects
				(font
					(size 0.635 0.635)
					(thickness 0.1778)
				)
			)
		)
		(property "Value" "47pF 50V 0402"
			(at 5.192415 2.266303 270)
			(unlocked yes)
			(layer "F.SilkS")
			(hide yes)
			(effects
				(font
					(size 0.635 0.635)
					(thickness 0.1778)
				)
			)
		)
		(sheetname "846-XXXXX_SCH_NEO-M9N_MODULE_2_RECEIVER")
		(sheetfile "846-XXXXX_SCH_NEO-M9N_MODULE_2_RECEIVER.kicad_sch")
		(duplicate_pad_numbers_are_jumpers no)
		(fp_line
			(start -0.9906 0.4826)
			(end -0.9906 -0.4826)
			(stroke
				(width 0.1778)
				(type solid)
			)
			(layer "F.SilkS")
		)
		(fp_line
			(start 0.9906 0.4826)
			(end -0.9906 0.4826)
			(stroke
				(width 0.1778)
				(type solid)
			)
			(layer "F.SilkS")
		)
		(fp_line
			(start 0.9906 0.4826)
			(end 0.9906 -0.4826)
			(stroke
				(width 0.1778)
				(type solid)
			)
			(layer "F.SilkS")
		)
		(fp_line
			(start 0.9906 -0.4826)
			(end -0.9906 -0.4826)
			(stroke
				(width 0.1778)
				(type solid)
			)
			(layer "F.SilkS")
		)
		(pad "1" smd rect
			(at -0.5 0 270)
			(size 0.5 0.5)
			(layers "F.Cu" "F.Mask" "F.Paste")
			(net "RF_ANT")
		)
		(pad "2" smd rect
			(at 0.5 0 270)
			(size 0.5 0.5)
			(layers "F.Cu" "F.Mask" "F.Paste")
			(net "RF_MODULE")
		)
	)
	(footprint "MyLibrary:CONN_NRPN042MAMS-RC"
		(locked yes)
		(layer "F.Cu")
		(at 178.26011 112.596105 180)
		(property "Reference" "J1"
			(at -1.332795 7.697577 0)
			(unlocked yes)
			(layer "F.SilkS")
			(effects
				(font
					(size 0.635 0.635)
					(thickness 0.1778)
				)
			)
		)
		(property "Value" "NRPN042MAMS-RC 2MM"
			(at 7.90874 8.595193 180)
			(unlocked yes)
			(layer "F.SilkS")
			(hide yes)
			(effects
				(font
					(size 0.635 0.635)
					(thickness 0.1778)
				)
			)
		)
		(sheetname "846-XXXXX_SCH_NEO-M9N_MODULE_2_RECEIVER")
		(sheetfile "846-XXXXX_SCH_NEO-M9N_MODULE_2_RECEIVER.kicad_sch")
		(duplicate_pad_numbers_are_jumpers no)
		(fp_line
			(start 6.301 6.768)
			(end -1.7526 6.768)
			(stroke
				(width 0.1778)
				(type solid)
			)
			(layer "F.SilkS")
		)
		(fp_line
			(start 6.301 -0.725)
			(end 6.301 6.768)
			(stroke
				(width 0.1778)
				(type solid)
			)
			(layer "F.SilkS")
		)
		(fp_line
			(start 6.301 -0.725)
			(end -1.7526 -0.725)
			(stroke
				(width 0.1778)
				(type solid)
			)
			(layer "F.SilkS")
		)
		(fp_line
			(start -1.7526 -0.725)
			(end -1.7526 6.768)
			(stroke
				(width 0.1778)
				(type solid)
			)
			(layer "F.SilkS")
		)
		(fp_rect
			(start -2.9464 0.5842)
			(end -1.778 -0.8128)
			(stroke
				(width 0)
				(type default)
			)
			(fill yes)
			(layer "F.SilkS")
		)
		(pad "1" smd rect
			(at 0 0 180)
			(size 2.95 1.02)
			(layers "F.Cu" "F.Mask" "F.Paste")
			(net "+5V")
		)
		(pad "2" smd rect
			(at 4.55 0 180)
			(size 2.95 1.02)
			(layers "F.Cu" "F.Mask" "F.Paste")
			(net "+3V3")
		)
		(pad "3" smd rect
			(at 0 2.00001 180)
			(size 2.95 1.02)
			(layers "F.Cu" "F.Mask" "F.Paste")
			(net "TX_GPS_CONN")
		)
		(pad "4" smd rect
			(at 4.55 2.00001 180)
			(size 2.95 1.02)
			(layers "F.Cu" "F.Mask" "F.Paste")
			(net "RST_GPS")
		)
		(pad "5" smd rect
			(at 0 4 180)
			(size 2.95 1.02)
			(layers "F.Cu" "F.Mask" "F.Paste")
			(net "RX_GPS_CONN")
		)
		(pad "6" smd rect
			(at 4.55 4 180)
			(size 2.95 1.02)
			(layers "F.Cu" "F.Mask" "F.Paste")
			(net "TP1")
		)
		(pad "7" smd rect
			(at 0 6.00001 180)
			(size 2.95 1.02)
			(layers "F.Cu" "F.Mask" "F.Paste")
		)
		(pad "8" smd rect
			(at 4.55 6.00001 180)
			(size 2.95 1.02)
			(layers "F.Cu" "F.Mask" "F.Paste")
			(net "GND")
		)
	)
	(footprint "MyLibrary:r0402"
		(layer "F.Cu")
		(at 128.0151 110.476095)
		(property "Reference" "R6"
			(at 0.577995 1.322443 0)
			(unlocked yes)
			(layer "F.SilkS")
			(effects
				(font
					(size 0.635 0.635)
					(thickness 0.178)
				)
			)
		)
		(property "Value" "0 ohm 0402"
			(at 6.79212 2.200402 0)
			(unlocked yes)
			(layer "F.SilkS")
			(hide yes)
			(effects
				(font
					(size 1.524 1.524)
					(thickness 0.254)
				)
			)
		)
		(sheetname "846-XXXXX_SCH_NEO-M9N_MODULE_2_RECEIVER")
		(sheetfile "846-XXXXX_SCH_NEO-M9N_MODULE_2_RECEIVER.kicad_sch")
		(duplicate_pad_numbers_are_jumpers no)
		(fp_line
			(start -0.9906 -0.5334)
			(end 0.9906 -0.5334)
			(stroke
				(width 0.1778)
				(type solid)
			)
			(layer "F.SilkS")
		)
		(fp_line
			(start -0.9906 0.5334)
			(end -0.9906 -0.5334)
			(stroke
				(width 0.1778)
				(type solid)
			)
			(layer "F.SilkS")
		)
		(fp_line
			(start -0.9906 0.5334)
			(end 0.9906 0.5334)
			(stroke
				(width 0.1778)
				(type solid)
			)
			(layer "F.SilkS")
		)
		(fp_line
			(start 0.9906 0.5334)
			(end 0.9906 -0.5334)
			(stroke
				(width 0.1778)
				(type solid)
			)
			(layer "F.SilkS")
		)
		(pad "1" smd rect
			(at -0.5 0)
			(size 0.5 0.6)
			(layers "F.Cu" "F.Mask" "F.Paste")
			(net "NetQ1_1")
		)
		(pad "2" smd rect
			(at 0.5 0)
			(size 0.5 0.6)
			(layers "F.Cu" "F.Mask" "F.Paste")
			(net "+5V")
		)
	)
	(footprint "MyLibrary:r0402"
		(layer "F.Cu")
		(at 137.5151 113.676095 180)
		(property "Reference" "R7"
			(at -0.577995 -1.222433 0)
			(unlocked yes)
			(layer "F.SilkS")
			(effects
				(font
					(size 0.635 0.635)
					(thickness 0.178)
				)
			)
		)
		(property "Value" "0 ohm 0402"
			(at 6.79212 2.200402 180)
			(unlocked yes)
			(layer "F.SilkS")
			(hide yes)
			(effects
				(font
					(size 1.524 1.524)
					(thickness 0.254)
				)
			)
		)
		(sheetname "846-XXXXX_SCH_NEO-M9N_MODULE_2_RECEIVER")
		(sheetfile "846-XXXXX_SCH_NEO-M9N_MODULE_2_RECEIVER.kicad_sch")
		(duplicate_pad_numbers_are_jumpers no)
		(fp_line
			(start 0.9906 0.5334)
			(end -0.9906 0.5334)
			(stroke
				(width 0.1778)
				(type solid)
			)
			(layer "F.SilkS")
		)
		(fp_line
			(start 0.9906 -0.5334)
			(end 0.9906 0.5334)
			(stroke
				(width 0.1778)
				(type solid)
			)
			(layer "F.SilkS")
		)
		(fp_line
			(start 0.9906 -0.5334)
			(end -0.9906 -0.5334)
			(stroke
				(width 0.1778)
				(type solid)
			)
			(layer "F.SilkS")
		)
		(fp_line
			(start -0.9906 -0.5334)
			(end -0.9906 0.5334)
			(stroke
				(width 0.1778)
				(type solid)
			)
			(layer "F.SilkS")
		)
		(pad "1" smd rect
			(at -0.5 0 180)
			(size 0.5 0.6)
			(layers "F.Cu" "F.Mask" "F.Paste")
			(net "LNA_EN")
		)
		(pad "2" smd rect
			(at 0.5 0 180)
			(size 0.5 0.6)
			(layers "F.Cu" "F.Mask" "F.Paste")
			(net "NetQ1_1")
		)
	)
	(footprint "MyLibrary:led0603"
		(layer "F.Cu")
		(at 159.0643 110.401495 90)
		(property "Reference" "LED1"
			(at 3.3032 0.173243 90)
			(unlocked yes)
			(layer "F.SilkS")
			(effects
				(font
					(size 0.635 0.635)
					(thickness 0.1778)
				)
			)
		)
		(property "Value" "Green"
			(at -3.032583 3.262745 0)
			(unlocked yes)
			(layer "F.SilkS")
			(hide yes)
			(effects
				(font
					(size 0.635 0.635)
					(thickness 0.1778)
				)
			)
		)
		(sheetname "846-XXXXX_SCH_NEO-M9N_MODULE_2_RECEIVER")
		(sheetfile "846-XXXXX_SCH_NEO-M9N_MODULE_2_RECEIVER.kicad_sch")
		(duplicate_pad_numbers_are_jumpers no)
		(fp_line
			(start 1.397 -0.635)
			(end 1.397 0.635)
			(stroke
				(width 0.1778)
				(type solid)
			)
			(layer "F.SilkS")
		)
		(fp_line
			(start -1.397 -0.635)
			(end 1.397 -0.635)
			(stroke
				(width 0.1778)
				(type solid)
			)
			(layer "F.SilkS")
		)
		(fp_line
			(start -1.397 -0.635)
			(end -1.397 0.635)
			(stroke
				(width 0.1778)
				(type solid)
			)
			(layer "F.SilkS")
		)
		(fp_line
			(start -0.03175 -0.12065)
			(end 0.08255 -0.00635)
			(stroke
				(width 0.0762)
				(type solid)
			)
			(layer "F.SilkS")
		)
		(fp_line
			(start -0.03175 -0.12065)
			(end -0.03175 0.10795)
			(stroke
				(width 0.0762)
				(type solid)
			)
			(layer "F.SilkS")
		)
		(fp_line
			(start 0.08255 -0.00635)
			(end -0.03175 0.10795)
			(stroke
				(width 0.0762)
				(type solid)
			)
			(layer "F.SilkS")
		)
		(fp_line
			(start -1.397 0.635)
			(end 1.397 0.635)
			(stroke
				(width 0.1778)
				(type solid)
			)
			(layer "F.SilkS")
		)
		(fp_rect
			(start -0.03211 0.0482)
			(end 0.03698 -0.05275)
			(stroke
				(width 0)
				(type default)
			)
			(fill yes)
			(layer "F.SilkS")
		)
		(pad "1" smd rect
			(at -0.75 0 90)
			(size 0.8 0.8)
			(layers "F.Cu" "F.Mask" "F.Paste")
			(net "+5V")
		)
		(pad "2" smd rect
			(at 0.75 0 90)
			(size 0.8 0.8)
			(layers "F.Cu" "F.Mask" "F.Paste")
			(net "NetLED1_2")
		)
	)
	(footprint "MyLibrary:r0402"
		(layer "F.Cu")
		(at 124.9151 110.476095 180)
		(property "Reference" "R9"
			(at 0.221995 -1.322443 0)
			(unlocked yes)
			(layer "F.SilkS")
			(effects
				(font
					(size 0.635 0.635)
					(thickness 0.178)
				)
			)
		)
		(property "Value" "0 ohm 0402"
			(at 6.79212 2.200402 180)
			(unlocked yes)
			(layer "F.SilkS")
			(hide yes)
			(effects
				(font
					(size 1.524 1.524)
					(thickness 0.254)
				)
			)
		)
		(sheetname "846-XXXXX_SCH_NEO-M9N_MODULE_2_RECEIVER")
		(sheetfile "846-XXXXX_SCH_NEO-M9N_MODULE_2_RECEIVER.kicad_sch")
		(duplicate_pad_numbers_are_jumpers no)
		(fp_line
			(start 0.9906 0.5334)
			(end -0.9906 0.5334)
			(stroke
				(width 0.1778)
				(type solid)
			)
			(layer "F.SilkS")
		)
		(fp_line
			(start 0.9906 -0.5334)
			(end 0.9906 0.5334)
			(stroke
				(width 0.1778)
				(type solid)
			)
			(layer "F.SilkS")
		)
		(fp_line
			(start 0.9906 -0.5334)
			(end -0.9906 -0.5334)
			(stroke
				(width 0.1778)
				(type solid)
			)
			(layer "F.SilkS")
		)
		(fp_line
			(start -0.9906 -0.5334)
			(end -0.9906 0.5334)
			(stroke
				(width 0.1778)
				(type solid)
			)
			(layer "F.SilkS")
		)
		(pad "1" smd rect
			(at -0.5 0 180)
			(size 0.5 0.6)
			(layers "F.Cu" "F.Mask" "F.Paste")
			(net "NetQ1_1")
		)
		(pad "2" smd rect
			(at 0.5 0 180)
			(size 0.5 0.6)
			(layers "F.Cu" "F.Mask" "F.Paste")
			(net "GND")
		)
	)
	(footprint "MyLibrary:CONN_131-3711-301"
		(locked yes)
		(layer "F.Cu")
		(at 120.70511 101.076085 -90)
		(property "Reference" "J2"
			(at -4.777547 -3.387785 0)
			(unlocked yes)
			(layer "F.SilkS")
			(effects
				(font
					(size 0.635 0.635)
					(thickness 0.1778)
				)
			)
		)
		(property "Value" "SMB_131-3711-301"
			(at 7.55288 12.885653 270)
			(unlocked yes)
			(layer "F.SilkS")
			(hide yes)
			(effects
				(font
					(size 0.635 0.635)
					(thickness 0.1778)
				)
			)
		)
		(sheetname "846-XXXXX_SCH_NEO-M9N_MODULE_2_RECEIVER")
		(sheetfile "846-XXXXX_SCH_NEO-M9N_MODULE_2_RECEIVER.kicad_sch")
		(duplicate_pad_numbers_are_jumpers no)
		(fp_line
			(start -3.8 3.8)
			(end -3.8 -3.8)
			(stroke
				(width 0.1778)
				(type solid)
			)
			(layer "F.SilkS")
		)
		(fp_line
			(start 3.8 3.8)
			(end -3.8 3.8)
			(stroke
				(width 0.1778)
				(type solid)
			)
			(layer "F.SilkS")
		)
		(fp_line
			(start 3.8 3.8)
			(end 3.8 -3.8)
			(stroke
				(width 0.1778)
				(type solid)
			)
			(layer "F.SilkS")
		)
		(fp_line
			(start 3.8 -3.8)
			(end -3.8 -3.8)
			(stroke
				(width 0.1778)
				(type solid)
			)
			(layer "F.SilkS")
		)
		(pad "" smd custom
			(at -3.58131 3.55583)
			(size 0.000001 0.000001)
			(layers "F.Cu" "F.Mask" "F.Paste")
			(solder_paste_margin -0.2)
			(thermal_bridge_angle 90)
			(options
				(clearance outline)
				(anchor circle)
			)
			(primitives
				(gr_poly
					(pts
						(xy 0 0) (xy 0 2.3622)
						(arc
							(start 1.914553 2.3622)
							(mid 3.556 1.5367)
							(end 5.197447 2.3622)
						)
						(xy 5.19745 2.3622) (xy 7.112 2.3622) (xy 7.112 0)
					)
					(width 0)
					(fill yes)
				)
			)
		)
		(pad "" smd custom
			(at -0.86351 -0.00017)
			(size 0.000001 0.000001)
			(layers "F.Cu" "F.Mask" "F.Paste")
			(solder_paste_margin -0.2)
			(thermal_bridge_angle 90)
			(options
				(clearance outline)
				(anchor circle)
			)
			(primitives
				(gr_poly
					(pts
						(arc
							(start 0 0)
							(mid -0.610657 0.252943)
							(end -0.8636 0.8636)
						)
						(arc
							(start -0.8636 0.8636)
							(mid -0.610657 1.474257)
							(end 0 1.7272)
						)
						(arc
							(start 0 1.7272)
							(mid 0.610657 1.474257)
							(end 0.8636 0.8636)
						)
						(arc
							(start 0.8636 0.8636)
							(mid 0.610657 0.252943)
							(end 0 0)
						)
					)
					(width 0)
					(fill yes)
				)
			)
		)
		(pad "" smd custom
			(at 1.21929 3.55583)
			(size 0.000001 0.000001)
			(layers "F.Cu" "F.Mask" "F.Paste")
			(solder_paste_margin -0.2)
			(thermal_bridge_angle 90)
			(options
				(clearance outline)
				(anchor circle)
			)
			(primitives
				(gr_poly
					(pts
						(xy 0 0) (xy 0 2.3622) (xy 7.112 2.3622) (xy 7.112 0)
						(arc
							(start 5.197447 0)
							(mid 3.556 0.8255)
							(end 1.914553 0)
						)
						(xy 1.91455 0)
					)
					(width 0)
					(fill yes)
				)
			)
		)
		(pad "1" smd circle
			(at 0.00009 -0.00017 270)
			(size 1 1)
			(layers "F.Cu" "F.Mask" "F.Paste")
			(net "RF_ANT")
			(solder_mask_margin 0)
			(thermal_bridge_angle 90)
		)
		(pad "2" smd rect
			(at -2.794 0.254 270)
			(size 1 5)
			(layers "F.Cu" "F.Mask" "F.Paste")
			(net "GND")
			(solder_mask_margin 0)
		)
		(pad "3" smd rect
			(at 2.91616 0 270)
			(size 1 5)
			(layers "F.Cu" "F.Mask" "F.Paste")
			(net "GND")
			(solder_mask_margin 0)
		)
	)
	(footprint "MyLibrary:TP1MM"
		(layer "F.Cu")
		(at 148.2151 95.576095)
		(property "Reference" "TP2"
			(at 0.122433 -1.677805 90)
			(unlocked yes)
			(layer "F.SilkS")
			(effects
				(font
					(size 0.635 0.635)
					(thickness 0.1778)
				)
			)
		)
		(property "Value" "1MM"
			(at -2.092793 1.790085 270)
			(unlocked yes)
			(layer "F.SilkS")
			(hide yes)
			(effects
				(font
					(size 0.635 0.635)
					(thickness 0.1778)
				)
			)
		)
		(sheetname "846-XXXXX_SCH_NEO-M9N_MODULE_2_RECEIVER")
		(sheetfile "846-XXXXX_SCH_NEO-M9N_MODULE_2_RECEIVER.kicad_sch")
		(duplicate_pad_numbers_are_jumpers no)
		(pad "1" smd circle
			(at 0 0)
			(size 1 1)
			(layers "F.Cu" "F.Mask" "F.Paste")
			(net "USB_DM")
			(solder_paste_margin -100)
			(thermal_bridge_angle 90)
		)
	)
)
